(kicad_pcb
	(version 20260206)
	(generator "pcbnew")
	(generator_version "10.0")
	(general
		(thickness 1.6)
		(legacy_teardrops no)
	)
	(paper "A4")
	(title_block
		(title "04192023_DAF0TMB3IC0_F0TG_MB_C_brd_V02_OCP.brd")
		(comment 1 "Grand Teton / footprints 2183-2187 of 8354")
	)
	(layers
		(0 "F.Cu" signal "TOP")
		(4 "In1.Cu" signal "GND")
		(6 "In2.Cu" signal "IN1")
		(8 "In3.Cu" signal "GND1")
		(10 "In4.Cu" signal "IN2")
		(12 "In5.Cu" signal "GND2")
		(14 "In6.Cu" signal "IN3")
		(16 "In7.Cu" signal "GND3")
		(18 "In8.Cu" signal "VCC")
		(20 "In9.Cu" signal "VCC1")
		(22 "In10.Cu" signal "GND4")
		(24 "In11.Cu" signal "IN4")
		(26 "In12.Cu" signal "GND5")
		(28 "In13.Cu" signal "IN5")
		(30 "In14.Cu" signal "GND6")
		(32 "In15.Cu" signal "IN6")
		(34 "In16.Cu" signal "GND7")
		(2 "B.Cu" signal "BOTTOM")
		(9 "F.Adhes" user "F.Adhesive")
		(11 "B.Adhes" user "B.Adhesive")
		(13 "F.Paste" user "Package Geometry/Pastemask Top")
		(15 "B.Paste" user "Package Geometry/Pastemask Bottom")
		(5 "F.SilkS" user "Ref Des/Silkscreen Top")
		(7 "B.SilkS" user "Ref Des/Silkscreen Bottom")
		(1 "F.Mask" user "Board Geometry/Soldermask Top")
		(3 "B.Mask" user "Board Geometry/Soldermask Bottom")
		(17 "Dwgs.User" user "User.Drawings")
		(19 "Cmts.User" user "User.Comments")
		(21 "Eco1.User" user "User.Eco1")
		(23 "Eco2.User" user "User.Eco2")
		(25 "Edge.Cuts" user "Board Geometry/Outline")
		(27 "Margin" user)
		(31 "F.CrtYd" user "Package Geometry/Place Bound Top")
		(29 "B.CrtYd" user "Package Geometry/Place Bound Bottom")
		(35 "F.Fab" user "Ref Des/Assembly Top")
		(33 "B.Fab" user "Ref Des/Assembly Bottom")
	)
	(footprint ""
		(layer "F.Cu")
		(at 103.729282 -339.939376)
		(property "Reference" "PU33"
			(at -3.018282 -7.632954 0)
			(unlocked yes)
			(layer "F.SilkS")
			(effects
				(font
					(size 0.7874 0.5842)
					(thickness 0.1524)
				)
				(justify left)
			)
		)
		(property "Value" ""
			(at 0 0 0)
			(layer "F.Fab")
			(effects
				(font
					(size 1.27 1.27)
				)
			)
		)
		(duplicate_pad_numbers_are_jumpers no)
		(fp_line
			(start -2.500122 -2.999994)
			(end -2.24409 -2.999994)
			(stroke
				(width 0.1524)
				(type default)
			)
			(layer "F.SilkS")
		)
		(fp_line
			(start -2.500122 -2.529078)
			(end -2.500122 -2.999994)
			(stroke
				(width 0.1524)
				(type default)
			)
			(layer "F.SilkS")
		)
		(fp_line
			(start -2.500122 0.6604)
			(end -2.500122 0.229108)
			(stroke
				(width 0.1524)
				(type default)
			)
			(layer "F.SilkS")
		)
		(fp_line
			(start -2.500122 2.999994)
			(end -2.500122 2.339594)
			(stroke
				(width 0.1524)
				(type default)
			)
			(layer "F.SilkS")
		)
		(fp_line
			(start -2.2987 2.999994)
			(end -2.500122 2.999994)
			(stroke
				(width 0.1524)
				(type default)
			)
			(layer "F.SilkS")
		)
		(fp_line
			(start 2.31394 -2.999994)
			(end 2.500122 -2.999994)
			(stroke
				(width 0.1524)
				(type default)
			)
			(layer "F.SilkS")
		)
		(fp_line
			(start 2.500122 -2.999994)
			(end 2.500122 -2.44348)
			(stroke
				(width 0.1524)
				(type default)
			)
			(layer "F.SilkS")
		)
		(fp_line
			(start 2.500122 2.339594)
			(end 2.500122 2.999994)
			(stroke
				(width 0.1524)
				(type default)
			)
			(layer "F.SilkS")
		)
		(fp_line
			(start 2.500122 2.999994)
			(end 2.2987 2.999994)
			(stroke
				(width 0.1524)
				(type default)
			)
			(layer "F.SilkS")
		)
		(fp_poly
			(pts
				(xy -2.770124 -2.400046) (xy -3.443732 -2.624582) (xy -2.99466 -3.073654)
			)
			(stroke
				(width 0)
				(type default)
			)
			(fill yes)
			(layer "F.SilkS")
		)
		(fp_line
			(start -2.500122 -2.999994)
			(end 2.500122 -2.999994)
			(stroke
				(width 0.1)
				(type default)
			)
			(layer "F.Fab")
		)
		(fp_line
			(start -2.500122 2.999994)
			(end -2.500122 -2.999994)
			(stroke
				(width 0.1)
				(type default)
			)
			(layer "F.Fab")
		)
		(fp_line
			(start 2.500122 -2.999994)
			(end 2.500122 2.999994)
			(stroke
				(width 0.1)
				(type default)
			)
			(layer "F.Fab")
		)
		(fp_line
			(start 2.500122 2.999994)
			(end -2.500122 2.999994)
			(stroke
				(width 0.1)
				(type default)
			)
			(layer "F.Fab")
		)
		(fp_poly
			(pts
				(xy -4.218432 -2.783078) (xy -4.218432 -1.767078) (xy -3.202432 -2.275078)
			)
			(stroke
				(width 0)
				(type default)
			)
			(fill yes)
			(layer "F.Fab")
		)
		(pad "1" smd rect
			(at -2.400046 -2.275078 90)
			(size 0.2286 0.6096)
			(layers "F.Cu" "F.Mask" "F.Paste")
			(net "PVDDCR_CPU1_P1_VOS6")
		)
		(pad "2" smd rect
			(at -2.400046 -1.82499 90)
			(size 0.2286 0.6096)
			(layers "F.Cu" "F.Mask" "F.Paste")
			(net "GND")
		)
		(pad "3" smd rect
			(at -2.400046 -1.374902 90)
			(size 0.2286 0.6096)
			(layers "F.Cu" "F.Mask" "F.Paste")
			(net "PVDDCR_CPU1_P1_VCC6")
		)
		(pad "4" smd rect
			(at -2.400046 -0.925068 90)
			(size 0.2286 0.6096)
			(layers "F.Cu" "F.Mask" "F.Paste")
			(net "PVDDCR_CPU1_P1_PVCC")
		)
		(pad "5" smd rect
			(at -2.400046 -0.47498 90)
			(size 0.2286 0.6096)
			(layers "F.Cu" "F.Mask" "F.Paste")
			(net "GND")
		)
		(pad "6" smd rect
			(at -2.400046 -0.024892 90)
			(size 0.2286 0.6096)
			(layers "F.Cu" "F.Mask" "F.Paste")
			(net "NC_PVDDCR_CPU1_P1_GL1_6")
		)
		(pad "7_9-20_24" smd circle
			(at 0 1.150112 90)
			(size 0 0)
			(layers "F.Cu" "F.Mask" "F.Paste")
			(net "GND")
		)
		(pad "10_19" smd rect
			(at 0 2.899918 90)
			(size 0.6096 4.318)
			(layers "F.Cu" "F.Mask" "F.Paste")
			(net "SW_PVDDCR_CPU1_P1_SW6")
		)
		(pad "25_29" smd rect
			(at 1.549908 -1.279906 270)
			(size 2.0574 2.3114)
			(layers "F.Cu" "F.Mask" "F.Paste")
			(net "SW_P12V_AUX_PVDDCR_CPU1_P1_FLT")
		)
		(pad "30" smd rect
			(at 2.05994 -2.899918)
			(size 0.2286 0.6096)
			(layers "F.Cu" "F.Mask" "F.Paste")
			(net "SW_P12V_AUX_PVDDCR_CPU1_P1_FLT")
		)
		(pad "31" smd rect
			(at 1.610106 -2.899918)
			(size 0.2286 0.6096)
			(layers "F.Cu" "F.Mask" "F.Paste")
			(net "NC_PVDDCR_CPU1_P1_DNC6")
		)
		(pad "32" smd rect
			(at 1.160018 -2.899918)
			(size 0.2286 0.6096)
			(layers "F.Cu" "F.Mask" "F.Paste")
			(net "SW_PVDDCR_CPU1_P1_BOOTR6")
		)
		(pad "33" smd rect
			(at 0.70993 -2.899918)
			(size 0.2286 0.6096)
			(layers "F.Cu" "F.Mask" "F.Paste")
			(net "SW_PVDDCR_CPU1_P1_BOOT6")
		)
		(pad "34" smd rect
			(at 0.260096 -2.899918)
			(size 0.2286 0.6096)
			(layers "F.Cu" "F.Mask" "F.Paste")
			(net "PVDDCR_CPU1_P1_PWM6")
		)
		(pad "35" smd rect
			(at -0.189992 -2.899918)
			(size 0.2286 0.6096)
			(layers "F.Cu" "F.Mask" "F.Paste")
			(net "PVDDCR_CPU1_P1_VCC6")
		)
		(pad "36" smd rect
			(at -0.64008 -2.899918)
			(size 0.2286 0.6096)
			(layers "F.Cu" "F.Mask" "F.Paste")
			(net "PVDDCR_CPU1_P1_TEMP0")
		)
		(pad "37" smd rect
			(at -1.089914 -2.899918)
			(size 0.2286 0.6096)
			(layers "F.Cu" "F.Mask" "F.Paste")
			(net "PVDDCR_CPU1_P1_LSET6")
		)
		(pad "38" smd rect
			(at -1.540002 -2.899918)
			(size 0.2286 0.6096)
			(layers "F.Cu" "F.Mask" "F.Paste")
			(net "PVDDCR_CPU1_P1_IMON6")
		)
		(pad "39" smd rect
			(at -1.99009 -2.899918)
			(size 0.2286 0.6096)
			(layers "F.Cu" "F.Mask" "F.Paste")
			(net "PVDDCR_CPU1_P1_VCCS")
		)
		(pad "40" smd rect
			(at -0.87503 -1.27508)
			(size 1.7526 1.9558)
			(layers "F.Cu" "F.Mask" "F.Paste")
			(net "GND")
		)
		(pad "41" smd rect
			(at -1.525016 0.249936 270)
			(size 0.3048 0.4572)
			(layers "F.Cu" "F.Mask" "F.Paste")
			(net "NC_PVDDCR_CPU1_P1_GL2_6")
		)
		(zone
			(layer "F.Cu")
			(hatch none 0.5)
			(connect_pads
				(clearance 0)
			)
			(min_thickness 0.25)
			(keepout
				(tracks not_allowed)
				(vias allowed)
				(pads allowed)
				(copperpour not_allowed)
				(footprints allowed)
			)
			(placement
				(enabled no)
				(sheetname "")
			)
			(fill
				(thermal_gap 0.5)
				(thermal_bridge_width 0.5)
				(island_removal_mode 0)
			)
			(polygon
				(pts
					(xy 101.22916 -337.356196) (xy 101.22916 -337.688682) (xy 106.229404 -337.688682) (xy 106.229404 -337.362038)
					(xy 105.939082 -337.362038) (xy 105.939082 -337.395058) (xy 101.519482 -337.395058) (xy 101.519482 -337.356196)
				)
			)
		)
		(zone
			(layer "F.Cu")
			(hatch none 0.5)
			(connect_pads
				(clearance 0)
			)
			(min_thickness 0.25)
			(keepout
				(tracks not_allowed)
				(vias allowed)
				(pads allowed)
				(copperpour not_allowed)
				(footprints allowed)
			)
			(placement
				(enabled no)
				(sheetname "")
			)
			(fill
				(thermal_gap 0.5)
				(thermal_bridge_width 0.5)
				(island_removal_mode 0)
			)
			(polygon
				(pts
					(xy 103.781352 -340.185756) (xy 103.781352 -342.243156) (xy 101.927152 -342.243156) (xy 101.927152 -342.00211)
					(xy 101.684836 -342.00211) (xy 101.684836 -342.483694) (xy 105.512616 -342.483694) (xy 105.512616 -342.298782)
					(xy 104.07269 -342.298782) (xy 104.07269 -340.139782) (xy 106.229404 -340.139782) (xy 106.229404 -339.8901)
					(xy 104.077008 -339.8901)
				)
			)
		)
	)
	(footprint ""
		(layer "F.Cu")
		(at 454.847452 -19.427698 -90)
		(property "Reference" "R3797"
			(at 0 0 270)
			(layer "F.SilkS")
			(hide yes)
			(effects
				(font
					(size 1.27 1.27)
				)
			)
		)
		(property "Value" ""
			(at 0 0 270)
			(layer "F.Fab")
			(effects
				(font
					(size 1.27 1.27)
				)
			)
		)
		(duplicate_pad_numbers_are_jumpers no)
		(fp_line
			(start -0.7874 0.4064)
			(end -0.7874 -0.4064)
			(stroke
				(width 0.1524)
				(type default)
			)
			(layer "F.SilkS")
		)
		(fp_line
			(start 0.7874 0.4064)
			(end -0.7874 0.4064)
			(stroke
				(width 0.1524)
				(type default)
			)
			(layer "F.SilkS")
		)
		(fp_line
			(start -0.7874 -0.4064)
			(end 0.7874 -0.4064)
			(stroke
				(width 0.1524)
				(type default)
			)
			(layer "F.SilkS")
		)
		(fp_line
			(start 0.7874 -0.4064)
			(end 0.7874 0.4064)
			(stroke
				(width 0.1524)
				(type default)
			)
			(layer "F.SilkS")
		)
		(fp_line
			(start -0.67945 0.3048)
			(end -0.67945 -0.305054)
			(stroke
				(width 0.1)
				(type default)
			)
			(layer "F.Fab")
		)
		(fp_line
			(start -0.12065 0.3048)
			(end -0.67945 0.3048)
			(stroke
				(width 0.1)
				(type default)
			)
			(layer "F.Fab")
		)
		(fp_line
			(start 0.120396 0.3048)
			(end 0.120396 0.2794)
			(stroke
				(width 0.1)
				(type default)
			)
			(layer "F.Fab")
		)
		(fp_line
			(start 0.67945 0.3048)
			(end 0.120396 0.3048)
			(stroke
				(width 0.1)
				(type default)
			)
			(layer "F.Fab")
		)
		(fp_line
			(start -0.12065 0.2794)
			(end -0.12065 0.3048)
			(stroke
				(width 0.1)
				(type default)
			)
			(layer "F.Fab")
		)
		(fp_line
			(start 0.120396 0.2794)
			(end -0.12065 0.2794)
			(stroke
				(width 0.1)
				(type default)
			)
			(layer "F.Fab")
		)
		(fp_line
			(start -0.12065 -0.2794)
			(end 0.12065 -0.2794)
			(stroke
				(width 0.1)
				(type default)
			)
			(layer "F.Fab")
		)
		(fp_line
			(start 0.12065 -0.2794)
			(end 0.12065 -0.3048)
			(stroke
				(width 0.1)
				(type default)
			)
			(layer "F.Fab")
		)
		(fp_line
			(start 0.12065 -0.3048)
			(end 0.67945 -0.3048)
			(stroke
				(width 0.1)
				(type default)
			)
			(layer "F.Fab")
		)
		(fp_line
			(start 0.67945 -0.3048)
			(end 0.67945 0.3048)
			(stroke
				(width 0.1)
				(type default)
			)
			(layer "F.Fab")
		)
		(fp_line
			(start -0.67945 -0.305054)
			(end -0.12065 -0.305054)
			(stroke
				(width 0.1)
				(type default)
			)
			(layer "F.Fab")
		)
		(fp_line
			(start -0.12065 -0.305054)
			(end -0.12065 -0.2794)
			(stroke
				(width 0.1)
				(type default)
			)
			(layer "F.Fab")
		)
		(pad "1" smd circle
			(at -0.40005 0 270)
			(size 0 0)
			(layers "F.Cu" "F.Mask" "F.Paste")
			(net "P3V3_AUX")
		)
		(pad "2" smd circle
			(at 0.40005 0 270)
			(size 0 0)
			(layers "F.Cu" "F.Mask" "F.Paste")
			(net "HP_LVC3_OCP_V3_1_P12V_PWRGD")
		)
	)
	(footprint ""
		(layer "F.Cu")
		(at 145.474944 -59.898534)
		(property "Reference" "R1622"
			(at 0 0 0)
			(layer "F.SilkS")
			(hide yes)
			(effects
				(font
					(size 1.27 1.27)
				)
			)
		)
		(property "Value" ""
			(at 0 0 0)
			(layer "F.Fab")
			(effects
				(font
					(size 1.27 1.27)
				)
			)
		)
		(duplicate_pad_numbers_are_jumpers no)
		(fp_line
			(start -0.7874 -0.4064)
			(end 0.7874 -0.4064)
			(stroke
				(width 0.1524)
				(type default)
			)
			(layer "F.SilkS")
		)
		(fp_line
			(start -0.7874 0.4064)
			(end -0.7874 -0.4064)
			(stroke
				(width 0.1524)
				(type default)
			)
			(layer "F.SilkS")
		)
		(fp_line
			(start 0.7874 -0.4064)
			(end 0.7874 0.4064)
			(stroke
				(width 0.1524)
				(type default)
			)
			(layer "F.SilkS")
		)
		(fp_line
			(start 0.7874 0.4064)
			(end -0.7874 0.4064)
			(stroke
				(width 0.1524)
				(type default)
			)
			(layer "F.SilkS")
		)
		(fp_line
			(start -0.67945 -0.305054)
			(end -0.12065 -0.305054)
			(stroke
				(width 0.1)
				(type default)
			)
			(layer "F.Fab")
		)
		(fp_line
			(start -0.67945 0.3048)
			(end -0.67945 -0.305054)
			(stroke
				(width 0.1)
				(type default)
			)
			(layer "F.Fab")
		)
		(fp_line
			(start -0.12065 -0.305054)
			(end -0.12065 -0.2794)
			(stroke
				(width 0.1)
				(type default)
			)
			(layer "F.Fab")
		)
		(fp_line
			(start -0.12065 -0.2794)
			(end 0.12065 -0.2794)
			(stroke
				(width 0.1)
				(type default)
			)
			(layer "F.Fab")
		)
		(fp_line
			(start -0.12065 0.2794)
			(end -0.12065 0.3048)
			(stroke
				(width 0.1)
				(type default)
			)
			(layer "F.Fab")
		)
		(fp_line
			(start -0.12065 0.3048)
			(end -0.67945 0.3048)
			(stroke
				(width 0.1)
				(type default)
			)
			(layer "F.Fab")
		)
		(fp_line
			(start 0.120396 0.2794)
			(end -0.12065 0.2794)
			(stroke
				(width 0.1)
				(type default)
			)
			(layer "F.Fab")
		)
		(fp_line
			(start 0.120396 0.3048)
			(end 0.120396 0.2794)
			(stroke
				(width 0.1)
				(type default)
			)
			(layer "F.Fab")
		)
		(fp_line
			(start 0.12065 -0.3048)
			(end 0.67945 -0.3048)
			(stroke
				(width 0.1)
				(type default)
			)
			(layer "F.Fab")
		)
		(fp_line
			(start 0.12065 -0.2794)
			(end 0.12065 -0.3048)
			(stroke
				(width 0.1)
				(type default)
			)
			(layer "F.Fab")
		)
		(fp_line
			(start 0.67945 -0.3048)
			(end 0.67945 0.3048)
			(stroke
				(width 0.1)
				(type default)
			)
			(layer "F.Fab")
		)
		(fp_line
			(start 0.67945 0.3048)
			(end 0.120396 0.3048)
			(stroke
				(width 0.1)
				(type default)
			)
			(layer "F.Fab")
		)
		(pad "1" smd circle
			(at -0.40005 0)
			(size 0 0)
			(layers "F.Cu" "F.Mask" "F.Paste")
			(net "P3V3_AUX")
		)
		(pad "2" smd circle
			(at 0.40005 0)
			(size 0 0)
			(layers "F.Cu" "F.Mask" "F.Paste")
			(net "JTAG_BMC_OE_N")
		)
	)
	(footprint ""
		(layer "F.Cu")
		(at 105.670096 -173.5201 90)
		(property "Reference" "PC301"
			(at 0 0 90)
			(layer "F.SilkS")
			(hide yes)
			(effects
				(font
					(size 1.27 1.27)
				)
			)
		)
		(property "Value" ""
			(at 0 0 90)
			(layer "F.Fab")
			(effects
				(font
					(size 1.27 1.27)
				)
			)
		)
		(duplicate_pad_numbers_are_jumpers no)
		(fp_line
			(start 0.7874 -0.4064)
			(end 0.7874 0.4064)
			(stroke
				(width 0.1524)
				(type default)
			)
			(layer "F.SilkS")
		)
		(fp_line
			(start -0.7874 -0.4064)
			(end 0.7874 -0.4064)
			(stroke
				(width 0.1524)
				(type default)
			)
			(layer "F.SilkS")
		)
		(fp_line
			(start 0.7874 0.4064)
			(end -0.7874 0.4064)
			(stroke
				(width 0.1524)
				(type default)
			)
			(layer "F.SilkS")
		)
		(fp_line
			(start -0.7874 0.4064)
			(end -0.7874 -0.4064)
			(stroke
				(width 0.1524)
				(type default)
			)
			(layer "F.SilkS")
		)
		(fp_line
			(start -0.12065 -0.305054)
			(end -0.12065 -0.2794)
			(stroke
				(width 0.1)
				(type default)
			)
			(layer "F.Fab")
		)
		(fp_line
			(start -0.67945 -0.305054)
			(end -0.12065 -0.305054)
			(stroke
				(width 0.1)
				(type default)
			)
			(layer "F.Fab")
		)
		(fp_line
			(start 0.67945 -0.3048)
			(end 0.67945 0.3048)
			(stroke
				(width 0.1)
				(type default)
			)
			(layer "F.Fab")
		)
		(fp_line
			(start 0.12065 -0.3048)
			(end 0.67945 -0.3048)
			(stroke
				(width 0.1)
				(type default)
			)
			(layer "F.Fab")
		)
		(fp_line
			(start 0.12065 -0.2794)
			(end 0.12065 -0.3048)
			(stroke
				(width 0.1)
				(type default)
			)
			(layer "F.Fab")
		)
		(fp_line
			(start -0.12065 -0.2794)
			(end 0.12065 -0.2794)
			(stroke
				(width 0.1)
				(type default)
			)
			(layer "F.Fab")
		)
		(fp_line
			(start 0.120396 0.2794)
			(end -0.12065 0.2794)
			(stroke
				(width 0.1)
				(type default)
			)
			(layer "F.Fab")
		)
		(fp_line
			(start -0.12065 0.2794)
			(end -0.12065 0.3048)
			(stroke
				(width 0.1)
				(type default)
			)
			(layer "F.Fab")
		)
		(fp_line
			(start 0.67945 0.3048)
			(end 0.120396 0.3048)
			(stroke
				(width 0.1)
				(type default)
			)
			(layer "F.Fab")
		)
		(fp_line
			(start 0.120396 0.3048)
			(end 0.120396 0.2794)
			(stroke
				(width 0.1)
				(type default)
			)
			(layer "F.Fab")
		)
		(fp_line
			(start -0.12065 0.3048)
			(end -0.67945 0.3048)
			(stroke
				(width 0.1)
				(type default)
			)
			(layer "F.Fab")
		)
		(fp_line
			(start -0.67945 0.3048)
			(end -0.67945 -0.305054)
			(stroke
				(width 0.1)
				(type default)
			)
			(layer "F.Fab")
		)
		(pad "1" smd circle
			(at -0.40005 0 90)
			(size 0 0)
			(layers "F.Cu" "F.Mask" "F.Paste")
			(net "SW_PVDDCR_CPU0_P1_BOOT4_RC")
		)
		(pad "2" smd circle
			(at 0.40005 0 90)
			(size 0 0)
			(layers "F.Cu" "F.Mask" "F.Paste")
			(net "SW_PVDDCR_CPU0_P1_PH4")
		)
	)
	(footprint ""
		(layer "F.Cu")
		(at 180.3908 -390.779)
		(property "Reference" "R1427"
			(at 0 0 0)
			(layer "F.SilkS")
			(hide yes)
			(effects
				(font
					(size 1.27 1.27)
				)
			)
		)
		(property "Value" ""
			(at 0 0 0)
			(layer "F.Fab")
			(effects
				(font
					(size 1.27 1.27)
				)
			)
		)
		(duplicate_pad_numbers_are_jumpers no)
		(fp_line
			(start -0.32512 -0.175006)
			(end 0.32512 -0.175006)
			(stroke
				(width 0.1)
				(type default)
			)
			(layer "F.Fab")
		)
		(fp_line
			(start -0.32512 0.175006)
			(end -0.32512 -0.175006)
			(stroke
				(width 0.1)
				(type default)
			)
			(layer "F.Fab")
		)
		(fp_line
			(start 0.32512 -0.175006)
			(end 0.32512 0.175006)
			(stroke
				(width 0.1)
				(type default)
			)
			(layer "F.Fab")
		)
		(fp_line
			(start 0.32512 0.175006)
			(end -0.32512 0.175006)
			(stroke
				(width 0.1)
				(type default)
			)
			(layer "F.Fab")
		)
		(pad "1" smd rect
			(at -0.2667 0)
			(size 0.3048 0.381)
			(layers "F.Cu" "F.Mask" "F.Paste")
			(net "RXDET_BYP_RT_CPU1_P2")
		)
		(pad "2" smd rect
			(at 0.2667 0 180)
			(size 0.3048 0.381)
			(layers "F.Cu" "F.Mask" "F.Paste")
			(net "GND")
		)
	)
)
